(kicad_pcb
	(version 20260206)
	(generator "pcbnew")
	(generator_version "10.0")
	(general
		(thickness 1.6)
		(legacy_teardrops no)
	)
	(paper "A4")
	(title_block
		(title "v1-chassis-manager — T6M_CM_d_v01_1031_1645.brd")
		(comment 1 "Open CloudServer (Microsoft) / footprints 2043-2051 of 2512")
	)
	(layers
		(0 "F.Cu" signal "TOP")
		(4 "In1.Cu" signal "GND1")
		(6 "In2.Cu" signal "IN1")
		(8 "In3.Cu" signal "VCC1")
		(10 "In4.Cu" signal "VCC2")
		(12 "In5.Cu" signal "GND2")
		(14 "In6.Cu" signal "IN2")
		(16 "In7.Cu" signal "IN3")
		(18 "In8.Cu" signal "GND3")
		(2 "B.Cu" signal "BOTTOM")
		(9 "F.Adhes" user "F.Adhesive")
		(11 "B.Adhes" user "B.Adhesive")
		(13 "F.Paste" user "Package Geometry/Pastemask Top")
		(15 "B.Paste" user "Package Geometry/Pastemask Bottom")
		(5 "F.SilkS" user "Ref Des/Silkscreen Top")
		(7 "B.SilkS" user "Ref Des/Silkscreen Bottom")
		(1 "F.Mask" user "Board Geometry/Soldermask Top")
		(3 "B.Mask" user "Board Geometry/Soldermask Bottom")
		(17 "Dwgs.User" user "User.Drawings")
		(19 "Cmts.User" user "User.Comments")
		(21 "Eco1.User" user "User.Eco1")
		(23 "Eco2.User" user "User.Eco2")
		(25 "Edge.Cuts" user "Board Geometry/Outline")
		(27 "Margin" user)
		(31 "F.CrtYd" user "Package Geometry/Place Bound Top")
		(29 "B.CrtYd" user "Package Geometry/Place Bound Bottom")
		(35 "F.Fab" user "Ref Des/Assembly Top")
		(33 "B.Fab" user "Ref Des/Assembly Bottom")
	)
	(footprint ""
		(layer "B.Cu")
		(at 153.578814 -67.232022 90)
		(property "Reference" "C360"
			(at 0.02159 5.137912 270)
			(unlocked yes)
			(layer "B.SilkS")
			(effects
				(font
					(size 0.7874 0.5842)
					(thickness 0.1524)
				)
				(justify left mirror)
			)
		)
		(property "Value" ""
			(at 0 0 90)
			(layer "B.Fab")
			(effects
				(font
					(size 1.27 1.27)
				)
				(justify mirror)
			)
		)
		(duplicate_pad_numbers_are_jumpers no)
		(fp_line
			(start 0.7874 -0.4064)
			(end -0.7874 -0.4064)
			(stroke
				(width 0.1524)
				(type default)
			)
			(layer "B.SilkS")
		)
		(fp_line
			(start -0.7874 -0.4064)
			(end -0.7874 0.4064)
			(stroke
				(width 0.1524)
				(type default)
			)
			(layer "B.SilkS")
		)
		(fp_line
			(start 0 0.381)
			(end 0 -0.381)
			(stroke
				(width 0.1524)
				(type default)
			)
			(layer "B.SilkS")
		)
		(fp_line
			(start 0.7874 0.4064)
			(end 0.7874 -0.4064)
			(stroke
				(width 0.1524)
				(type default)
			)
			(layer "B.SilkS")
		)
		(fp_line
			(start -0.7874 0.4064)
			(end 0.7874 0.4064)
			(stroke
				(width 0.1524)
				(type default)
			)
			(layer "B.SilkS")
		)
		(fp_poly
			(pts
				(xy 0.5334 0.254) (xy 0.635 0.254) (xy 0.635 0.2286) (xy 0.635 -0.254) (xy 0.5334 -0.254) (xy 0.5334 -0.2794)
				(xy -0.5334 -0.2794) (xy -0.5334 -0.254) (xy -0.635 -0.254) (xy -0.635 0.254) (xy -0.5334 0.254)
				(xy -0.5334 0.2794) (xy 0.508 0.2794) (xy 0.5334 0.2794)
			)
			(stroke
				(width 0)
				(type default)
			)
			(fill no)
			(layer "B.CrtYd")
		)
		(pad "1" smd rect
			(at -0.40005 0 270)
			(size 0.4572 0.508)
			(layers "B.Cu" "B.Mask" "B.Paste")
			(net "P1V8_SATA_VAA1_NODE1")
		)
		(pad "2" smd rect
			(at 0.40005 0 270)
			(size 0.4572 0.508)
			(layers "B.Cu" "B.Mask" "B.Paste")
			(net "GND")
		)
	)
	(footprint ""
		(layer "B.Cu")
		(at 151.62276 -184.951624 90)
		(property "Reference" "R894"
			(at 4.357624 -3.26517 270)
			(unlocked yes)
			(layer "B.SilkS")
			(effects
				(font
					(size 0.7874 0.5842)
					(thickness 0.1524)
				)
				(justify left mirror)
			)
		)
		(property "Value" ""
			(at 0 0 90)
			(layer "B.Fab")
			(effects
				(font
					(size 1.27 1.27)
				)
				(justify mirror)
			)
		)
		(duplicate_pad_numbers_are_jumpers no)
		(fp_line
			(start 0.7874 -0.4064)
			(end -0.7874 -0.4064)
			(stroke
				(width 0.1524)
				(type default)
			)
			(layer "B.SilkS")
		)
		(fp_line
			(start -0.7874 -0.4064)
			(end -0.7874 0.4064)
			(stroke
				(width 0.1524)
				(type default)
			)
			(layer "B.SilkS")
		)
		(fp_line
			(start 0.7874 0.4064)
			(end 0.7874 -0.4064)
			(stroke
				(width 0.1524)
				(type default)
			)
			(layer "B.SilkS")
		)
		(fp_line
			(start -0.7874 0.4064)
			(end 0.7874 0.4064)
			(stroke
				(width 0.1524)
				(type default)
			)
			(layer "B.SilkS")
		)
		(fp_poly
			(pts
				(xy 0.508 0.2794) (xy 0.508 0.2286) (xy 0.635 0.2286) (xy 0.635 -0.254) (xy 0.5334 -0.254) (xy 0.5334 -0.2794)
				(xy -0.5334 -0.2794) (xy -0.5334 -0.254) (xy -0.635 -0.254) (xy -0.635 0.254) (xy -0.5334 0.254)
				(xy -0.5334 0.2794)
			)
			(stroke
				(width 0)
				(type default)
			)
			(fill no)
			(layer "B.CrtYd")
		)
		(pad "1" smd rect
			(at -0.40005 0 270)
			(size 0.4572 0.508)
			(layers "B.Cu" "B.Mask" "B.Paste")
			(net "T11_NODE4_EN")
		)
		(pad "2" smd rect
			(at 0.40005 0 270)
			(size 0.4572 0.508)
			(layers "B.Cu" "B.Mask" "B.Paste")
			(net "T11_NODE4_EN_R")
		)
	)
	(footprint ""
		(layer "B.Cu")
		(at 64.121538 -64.799718)
		(property "Reference" "C14"
			(at 0.00889 5.282946 0)
			(unlocked yes)
			(layer "B.SilkS")
			(effects
				(font
					(size 0.7874 0.5842)
					(thickness 0.1524)
				)
				(justify left mirror)
			)
		)
		(property "Value" ""
			(at 0 0 0)
			(layer "B.Fab")
			(effects
				(font
					(size 1.27 1.27)
				)
				(justify mirror)
			)
		)
		(duplicate_pad_numbers_are_jumpers no)
		(fp_line
			(start -0.7874 -0.4064)
			(end -0.7874 0.4064)
			(stroke
				(width 0.1524)
				(type default)
			)
			(layer "B.SilkS")
		)
		(fp_line
			(start -0.7874 0.4064)
			(end 0.7874 0.4064)
			(stroke
				(width 0.1524)
				(type default)
			)
			(layer "B.SilkS")
		)
		(fp_line
			(start 0 0.381)
			(end 0 -0.381)
			(stroke
				(width 0.1524)
				(type default)
			)
			(layer "B.SilkS")
		)
		(fp_line
			(start 0.7874 -0.4064)
			(end -0.7874 -0.4064)
			(stroke
				(width 0.1524)
				(type default)
			)
			(layer "B.SilkS")
		)
		(fp_line
			(start 0.7874 0.4064)
			(end 0.7874 -0.4064)
			(stroke
				(width 0.1524)
				(type default)
			)
			(layer "B.SilkS")
		)
		(fp_poly
			(pts
				(xy 0.5334 0.254) (xy 0.635 0.254) (xy 0.635 0.2286) (xy 0.635 -0.254) (xy 0.5334 -0.254) (xy 0.5334 -0.2794)
				(xy -0.5334 -0.2794) (xy -0.5334 -0.254) (xy -0.635 -0.254) (xy -0.635 0.254) (xy -0.5334 0.254)
				(xy -0.5334 0.2794) (xy 0.508 0.2794) (xy 0.5334 0.2794)
			)
			(stroke
				(width 0)
				(type default)
			)
			(fill no)
			(layer "B.CrtYd")
		)
		(pad "1" smd rect
			(at -0.40005 0 180)
			(size 0.4572 0.508)
			(layers "B.Cu" "B.Mask" "B.Paste")
			(net "N29180194")
		)
		(pad "2" smd rect
			(at 0.40005 0 180)
			(size 0.4572 0.508)
			(layers "B.Cu" "B.Mask" "B.Paste")
			(net "GND")
		)
	)
	(footprint ""
		(layer "B.Cu")
		(at 78.83144 -165.393624 180)
		(property "Reference" "R782"
			(at -30.555946 -20.931886 0)
			(unlocked yes)
			(layer "B.SilkS")
			(effects
				(font
					(size 0.7874 0.5842)
					(thickness 0.1524)
				)
				(justify left mirror)
			)
		)
		(property "Value" ""
			(at 0 0 0)
			(layer "B.Fab")
			(effects
				(font
					(size 1.27 1.27)
				)
				(justify mirror)
			)
		)
		(duplicate_pad_numbers_are_jumpers no)
		(fp_line
			(start 0.7874 0.4064)
			(end 0.7874 -0.4064)
			(stroke
				(width 0.1524)
				(type default)
			)
			(layer "B.SilkS")
		)
		(fp_line
			(start 0.7874 -0.4064)
			(end -0.7874 -0.4064)
			(stroke
				(width 0.1524)
				(type default)
			)
			(layer "B.SilkS")
		)
		(fp_line
			(start -0.7874 0.4064)
			(end 0.7874 0.4064)
			(stroke
				(width 0.1524)
				(type default)
			)
			(layer "B.SilkS")
		)
		(fp_line
			(start -0.7874 -0.4064)
			(end -0.7874 0.4064)
			(stroke
				(width 0.1524)
				(type default)
			)
			(layer "B.SilkS")
		)
		(fp_poly
			(pts
				(xy 0.508 0.2794) (xy 0.508 0.2286) (xy 0.635 0.2286) (xy 0.635 -0.254) (xy 0.5334 -0.254) (xy 0.5334 -0.2794)
				(xy -0.5334 -0.2794) (xy -0.5334 -0.254) (xy -0.635 -0.254) (xy -0.635 0.254) (xy -0.5334 0.254)
				(xy -0.5334 0.2794)
			)
			(stroke
				(width 0)
				(type default)
			)
			(fill no)
			(layer "B.CrtYd")
		)
		(pad "1" smd rect
			(at -0.40005 0)
			(size 0.4572 0.508)
			(layers "B.Cu" "B.Mask" "B.Paste")
			(net "SDC_WAKEUP")
		)
		(pad "2" smd rect
			(at 0.40005 0)
			(size 0.4572 0.508)
			(layers "B.Cu" "B.Mask" "B.Paste")
			(net "P3V3_NODE1")
		)
	)
	(footprint ""
		(layer "B.Cu")
		(at 69.649086 -131.280662 90)
		(property "Reference" "C255"
			(at -55.866538 -38.53434 270)
			(unlocked yes)
			(layer "B.SilkS")
			(effects
				(font
					(size 0.7874 0.5842)
					(thickness 0.1524)
				)
				(justify left mirror)
			)
		)
		(property "Value" ""
			(at 0 0 90)
			(layer "B.Fab")
			(effects
				(font
					(size 1.27 1.27)
				)
				(justify mirror)
			)
		)
		(duplicate_pad_numbers_are_jumpers no)
		(fp_line
			(start 0.7874 -0.4064)
			(end -0.7874 -0.4064)
			(stroke
				(width 0.1524)
				(type default)
			)
			(layer "B.SilkS")
		)
		(fp_line
			(start -0.7874 -0.4064)
			(end -0.7874 0.4064)
			(stroke
				(width 0.1524)
				(type default)
			)
			(layer "B.SilkS")
		)
		(fp_line
			(start 0 0.381)
			(end 0 -0.381)
			(stroke
				(width 0.1524)
				(type default)
			)
			(layer "B.SilkS")
		)
		(fp_line
			(start 0.7874 0.4064)
			(end 0.7874 -0.4064)
			(stroke
				(width 0.1524)
				(type default)
			)
			(layer "B.SilkS")
		)
		(fp_line
			(start -0.7874 0.4064)
			(end 0.7874 0.4064)
			(stroke
				(width 0.1524)
				(type default)
			)
			(layer "B.SilkS")
		)
		(fp_poly
			(pts
				(xy 0.5334 0.254) (xy 0.635 0.254) (xy 0.635 0.2286) (xy 0.635 -0.254) (xy 0.5334 -0.254) (xy 0.5334 -0.2794)
				(xy -0.5334 -0.2794) (xy -0.5334 -0.254) (xy -0.635 -0.254) (xy -0.635 0.254) (xy -0.5334 0.254)
				(xy -0.5334 0.2794) (xy 0.508 0.2794) (xy 0.5334 0.2794)
			)
			(stroke
				(width 0)
				(type default)
			)
			(fill no)
			(layer "B.CrtYd")
		)
		(pad "1" smd rect
			(at -0.40005 0 270)
			(size 0.4572 0.508)
			(layers "B.Cu" "B.Mask" "B.Paste")
			(net "P3V3_NODE1")
		)
		(pad "2" smd rect
			(at 0.40005 0 270)
			(size 0.4572 0.508)
			(layers "B.Cu" "B.Mask" "B.Paste")
			(net "GND")
		)
	)
	(footprint ""
		(layer "B.Cu")
		(at 171.846494 -120.607836 180)
		(property "Reference" "C790"
			(at 1.413002 4.142994 0)
			(unlocked yes)
			(layer "B.SilkS")
			(effects
				(font
					(size 0.7874 0.5842)
					(thickness 0.1524)
				)
				(justify mirror)
			)
		)
		(property "Value" ""
			(at 0 0 0)
			(layer "B.Fab")
			(effects
				(font
					(size 1.27 1.27)
				)
				(justify mirror)
			)
		)
		(duplicate_pad_numbers_are_jumpers no)
		(fp_line
			(start 1.2954 0.5842)
			(end 1.2954 -0.5842)
			(stroke
				(width 0.1524)
				(type default)
			)
			(layer "B.SilkS")
		)
		(fp_line
			(start 1.2954 -0.5842)
			(end -1.2954 -0.5842)
			(stroke
				(width 0.1524)
				(type default)
			)
			(layer "B.SilkS")
		)
		(fp_line
			(start 0 -0.5842)
			(end 0 0.5842)
			(stroke
				(width 0.1524)
				(type default)
			)
			(layer "B.SilkS")
		)
		(fp_line
			(start -1.2954 0.5842)
			(end 1.2954 0.5842)
			(stroke
				(width 0.1524)
				(type default)
			)
			(layer "B.SilkS")
		)
		(fp_line
			(start -1.2954 -0.5842)
			(end -1.2954 0.5842)
			(stroke
				(width 0.1524)
				(type default)
			)
			(layer "B.SilkS")
		)
		(fp_poly
			(pts
				(xy -0.8636 -0.4572) (xy -0.8636 -0.3556) (xy -1.143 -0.3556) (xy -1.143 0.3556) (xy -0.8636 0.3556)
				(xy -0.8636 0.4572) (xy 0.8636 0.4572) (xy 0.8636 0.3556) (xy 1.143 0.3556) (xy 1.143 -0.3556) (xy 0.8636 -0.3556)
				(xy 0.8636 -0.4572)
			)
			(stroke
				(width 0)
				(type default)
			)
			(fill no)
			(layer "B.CrtYd")
		)
		(fp_line
			(start 0.884936 0.504952)
			(end 0.884936 -0.504952)
			(stroke
				(width 0.1)
				(type default)
			)
			(layer "B.Fab")
		)
		(fp_line
			(start 0.884936 -0.504952)
			(end -0.884936 -0.504952)
			(stroke
				(width 0.1)
				(type default)
			)
			(layer "B.Fab")
		)
		(fp_line
			(start -0.884936 0.504952)
			(end 0.884936 0.504952)
			(stroke
				(width 0.1)
				(type default)
			)
			(layer "B.Fab")
		)
		(fp_line
			(start -0.884936 -0.504952)
			(end -0.884936 0.504952)
			(stroke
				(width 0.1)
				(type default)
			)
			(layer "B.Fab")
		)
		(pad "1" smd rect
			(at -0.7366 0 270)
			(size 0.7112 0.8128)
			(layers "B.Cu" "B.Mask" "B.Paste")
			(net "P3V3_STB_NODE1")
		)
		(pad "2" smd rect
			(at 0.7366 0 270)
			(size 0.7112 0.8128)
			(layers "B.Cu" "B.Mask" "B.Paste")
			(net "GND")
		)
	)
	(footprint ""
		(layer "B.Cu")
		(at 64.112648 -62.719966 180)
		(property "Reference" "R27"
			(at -0.01778 -5.286502 0)
			(unlocked yes)
			(layer "B.SilkS")
			(effects
				(font
					(size 0.7874 0.5842)
					(thickness 0.1524)
				)
				(justify left mirror)
			)
		)
		(property "Value" ""
			(at 0 0 0)
			(layer "B.Fab")
			(effects
				(font
					(size 1.27 1.27)
				)
				(justify mirror)
			)
		)
		(duplicate_pad_numbers_are_jumpers no)
		(fp_line
			(start 0.7874 0.4064)
			(end 0.7874 -0.4064)
			(stroke
				(width 0.1524)
				(type default)
			)
			(layer "B.SilkS")
		)
		(fp_line
			(start 0.7874 -0.4064)
			(end -0.7874 -0.4064)
			(stroke
				(width 0.1524)
				(type default)
			)
			(layer "B.SilkS")
		)
		(fp_line
			(start -0.7874 0.4064)
			(end 0.7874 0.4064)
			(stroke
				(width 0.1524)
				(type default)
			)
			(layer "B.SilkS")
		)
		(fp_line
			(start -0.7874 -0.4064)
			(end -0.7874 0.4064)
			(stroke
				(width 0.1524)
				(type default)
			)
			(layer "B.SilkS")
		)
		(fp_poly
			(pts
				(xy 0.508 0.2794) (xy 0.508 0.2286) (xy 0.635 0.2286) (xy 0.635 -0.254) (xy 0.5334 -0.254) (xy 0.5334 -0.2794)
				(xy -0.5334 -0.2794) (xy -0.5334 -0.254) (xy -0.635 -0.254) (xy -0.635 0.254) (xy -0.5334 0.254)
				(xy -0.5334 0.2794)
			)
			(stroke
				(width 0)
				(type default)
			)
			(fill no)
			(layer "B.CrtYd")
		)
		(pad "1" smd rect
			(at -0.40005 0)
			(size 0.4572 0.508)
			(layers "B.Cu" "B.Mask" "B.Paste")
			(net "PV_VDDR_NODE1")
		)
		(pad "2" smd rect
			(at 0.40005 0)
			(size 0.4572 0.508)
			(layers "B.Cu" "B.Mask" "B.Paste")
			(net "N29180194")
		)
	)
	(footprint ""
		(layer "B.Cu")
		(at 48.257206 -114.430302)
		(property "Reference" "PC13"
			(at 1.684782 -1.669288 0)
			(unlocked yes)
			(layer "B.SilkS")
			(effects
				(font
					(size 0.7874 0.5842)
					(thickness 0.1524)
				)
				(justify left mirror)
			)
		)
		(property "Value" ""
			(at 0 0 0)
			(layer "B.Fab")
			(effects
				(font
					(size 1.27 1.27)
				)
				(justify mirror)
			)
		)
		(duplicate_pad_numbers_are_jumpers no)
		(fp_line
			(start -2.2098 -0.9398)
			(end -2.2098 0.9398)
			(stroke
				(width 0.1524)
				(type default)
			)
			(layer "B.SilkS")
		)
		(fp_line
			(start -2.2098 0.9398)
			(end 2.2098 0.9398)
			(stroke
				(width 0.1524)
				(type default)
			)
			(layer "B.SilkS")
		)
		(fp_line
			(start 0 -0.9398)
			(end 0 0.9398)
			(stroke
				(width 0.1524)
				(type default)
			)
			(layer "B.SilkS")
		)
		(fp_line
			(start 2.2098 -0.9398)
			(end -2.2098 -0.9398)
			(stroke
				(width 0.1524)
				(type default)
			)
			(layer "B.SilkS")
		)
		(fp_line
			(start 2.2098 0.9398)
			(end 2.2098 -0.9398)
			(stroke
				(width 0.1524)
				(type default)
			)
			(layer "B.SilkS")
		)
		(fp_poly
			(pts
				(xy 1.6764 0.889) (xy 1.6764 0.7874) (xy 2.0574 0.7874) (xy 2.0574 -0.7874) (xy 1.6764 -0.7874)
				(xy 1.6764 -0.9398) (xy -1.6764 -0.9398) (xy -1.6764 -0.7874) (xy -2.0574 -0.7874) (xy -2.0574 0.7874)
				(xy -1.6764 0.7874) (xy -1.6764 0.9398) (xy 1.6764 0.9398)
			)
			(stroke
				(width 0)
				(type default)
			)
			(fill no)
			(layer "B.CrtYd")
		)
		(fp_line
			(start -1.700022 -0.899922)
			(end -1.700022 0.899922)
			(stroke
				(width 0.1)
				(type default)
			)
			(layer "B.Fab")
		)
		(fp_line
			(start -1.700022 0.899922)
			(end 1.700022 0.899922)
			(stroke
				(width 0.1)
				(type default)
			)
			(layer "B.Fab")
		)
		(fp_line
			(start 1.700022 -0.899922)
			(end -1.700022 -0.899922)
			(stroke
				(width 0.1)
				(type default)
			)
			(layer "B.Fab")
		)
		(fp_line
			(start 1.700022 0.899922)
			(end 1.700022 -0.899922)
			(stroke
				(width 0.1)
				(type default)
			)
			(layer "B.Fab")
		)
		(pad "1" smd rect
			(at -1.4732 0 180)
			(size 1.1684 1.5748)
			(layers "B.Cu" "B.Mask" "B.Paste")
			(net "P12V_AUX")
		)
		(pad "2" smd rect
			(at 1.4732 0 180)
			(size 1.1684 1.5748)
			(layers "B.Cu" "B.Mask" "B.Paste")
			(net "GND")
		)
	)
	(footprint ""
		(layer "B.Cu")
		(at 79.991204 -21.117306 90)
		(property "Reference" "C167"
			(at -5.827014 -0.770128 270)
			(unlocked yes)
			(layer "B.SilkS")
			(effects
				(font
					(size 0.7874 0.5842)
					(thickness 0.1524)
				)
				(justify left mirror)
			)
		)
		(property "Value" ""
			(at 0 0 90)
			(layer "B.Fab")
			(effects
				(font
					(size 1.27 1.27)
				)
				(justify mirror)
			)
		)
		(duplicate_pad_numbers_are_jumpers no)
		(fp_line
			(start 0.7874 -0.4064)
			(end -0.7874 -0.4064)
			(stroke
				(width 0.1524)
				(type default)
			)
			(layer "B.SilkS")
		)
		(fp_line
			(start -0.7874 -0.4064)
			(end -0.7874 0.4064)
			(stroke
				(width 0.1524)
				(type default)
			)
			(layer "B.SilkS")
		)
		(fp_line
			(start 0 0.381)
			(end 0 -0.381)
			(stroke
				(width 0.1524)
				(type default)
			)
			(layer "B.SilkS")
		)
		(fp_line
			(start 0.7874 0.4064)
			(end 0.7874 -0.4064)
			(stroke
				(width 0.1524)
				(type default)
			)
			(layer "B.SilkS")
		)
		(fp_line
			(start -0.7874 0.4064)
			(end 0.7874 0.4064)
			(stroke
				(width 0.1524)
				(type default)
			)
			(layer "B.SilkS")
		)
		(fp_poly
			(pts
				(xy 0.5334 0.254) (xy 0.635 0.254) (xy 0.635 0.2286) (xy 0.635 -0.254) (xy 0.5334 -0.254) (xy 0.5334 -0.2794)
				(xy -0.5334 -0.2794) (xy -0.5334 -0.254) (xy -0.635 -0.254) (xy -0.635 0.254) (xy -0.5334 0.254)
				(xy -0.5334 0.2794) (xy 0.508 0.2794) (xy 0.5334 0.2794)
			)
			(stroke
				(width 0)
				(type default)
			)
			(fill no)
			(layer "B.CrtYd")
		)
		(pad "1" smd rect
			(at -0.40005 0 270)
			(size 0.4572 0.508)
			(layers "B.Cu" "B.Mask" "B.Paste")
			(net "PV_VDDR_NODE1")
		)
		(pad "2" smd rect
			(at 0.40005 0 270)
			(size 0.4572 0.508)
			(layers "B.Cu" "B.Mask" "B.Paste")
			(net "GND")
		)
	)
)
